# T6G (Grand Teton) — schematic netlist excerpt (pin names and nets, part order shuffled) for the footprints in the layout excerpt that follows; sources: Cadence DE-HDL packaged netlist, KiCad conversion of 04192023_DAF0TMB3IC0_F0TG_MB_C_brd_V02_OCP.brd

C451  Q_CAP  0.1UF 10V 10% X7S  pkg C0201  page 356 : A = P0V9_CPU1_RT_2D ; B = GND
PC6624_1  Q_CAP  22UF 4V 20% X6S  pkg C0805  page 365 : A = P0V9_CPU1_RT_2D ; B = GND
C427  Q_CAP  0.1UF 10V 10% X7S  pkg C0201  page 345 : A = P0V9_CPU1_RT2_2A ; B = GND
PC303_4  Q_CAP  22UF 4V 20% X6S  pkg C0805  page 212 : A = PVDDCR_CPU0_P1 ; B = GND

(kicad_pcb
	(version 20260206)
	(generator "pcbnew")
	(generator_version "10.0")
	(general
		(thickness 1.6)
		(legacy_teardrops no)
	)
	(paper "A4")
	(title_block
		(title "04192023_DAF0TMB3IC0_F0TG_MB_C_brd_V02_OCP.brd")
		(comment 1 "Grand Teton / footprints 4962-4966 of 8354")
	)
	(layers
		(0 "F.Cu" signal "TOP")
		(4 "In1.Cu" signal "GND")
		(6 "In2.Cu" signal "IN1")
		(8 "In3.Cu" signal "GND1")
		(10 "In4.Cu" signal "IN2")
		(12 "In5.Cu" signal "GND2")
		(14 "In6.Cu" signal "IN3")
		(16 "In7.Cu" signal "GND3")
		(18 "In8.Cu" signal "VCC")
		(20 "In9.Cu" signal "VCC1")
		(22 "In10.Cu" signal "GND4")
		(24 "In11.Cu" signal "IN4")
		(26 "In12.Cu" signal "GND5")
		(28 "In13.Cu" signal "IN5")
		(30 "In14.Cu" signal "GND6")
		(32 "In15.Cu" signal "IN6")
		(34 "In16.Cu" signal "GND7")
		(2 "B.Cu" signal "BOTTOM")
		(9 "F.Adhes" user "F.Adhesive")
		(11 "B.Adhes" user "B.Adhesive")
		(13 "F.Paste" user "Package Geometry/Pastemask Top")
		(15 "B.Paste" user "Package Geometry/Pastemask Bottom")
		(5 "F.SilkS" user "Ref Des/Silkscreen Top")
		(7 "B.SilkS" user "Ref Des/Silkscreen Bottom")
		(1 "F.Mask" user "Board Geometry/Soldermask Top")
		(3 "B.Mask" user "Board Geometry/Soldermask Bottom")
		(17 "Dwgs.User" user "User.Drawings")
		(19 "Cmts.User" user "User.Comments")
		(21 "Eco1.User" user "User.Eco1")
		(23 "Eco2.User" user "User.Eco2")
		(25 "Edge.Cuts" user "Board Geometry/Outline")
		(27 "Margin" user)
		(31 "F.CrtYd" user "Package Geometry/Place Bound Top")
		(29 "B.CrtYd" user "Package Geometry/Place Bound Bottom")
		(35 "F.Fab" user "Ref Des/Assembly Top")
		(33 "B.Fab" user "Ref Des/Assembly Bottom")
	)
	(footprint ""
		(layer "B.Cu")
		(at 120.618504 -388.011162 -90)
		(property "Reference" "C451"
			(at 0 0 90)
			(layer "B.SilkS")
			(hide yes)
			(effects
				(font
					(size 1.27 1.27)
				)
				(justify mirror)
			)
		)
		(property "Value" ""
			(at 0 0 90)
			(layer "B.Fab")
			(effects
				(font
					(size 1.27 1.27)
				)
				(justify mirror)
			)
		)
		(duplicate_pad_numbers_are_jumpers no)
		(fp_line
			(start -0.299974 0.150114)
			(end 0.299974 0.150114)
			(stroke
				(width 0.1)
				(type default)
			)
			(layer "B.Fab")
		)
		(fp_line
			(start 0.299974 0.150114)
			(end 0.299974 -0.150114)
			(stroke
				(width 0.1)
				(type default)
			)
			(layer "B.Fab")
		)
		(fp_line
			(start -0.299974 -0.150114)
			(end -0.299974 0.150114)
			(stroke
				(width 0.1)
				(type default)
			)
			(layer "B.Fab")
		)
		(fp_line
			(start 0.299974 -0.150114)
			(end -0.299974 -0.150114)
			(stroke
				(width 0.1)
				(type default)
			)
			(layer "B.Fab")
		)
		(pad "1" smd rect
			(at 0.2667 0 90)
			(size 0.3048 0.381)
			(layers "B.Cu" "B.Mask" "B.Paste")
			(net "P0V9_CPU1_RT_2D")
		)
		(pad "2" smd rect
			(at -0.2667 0 90)
			(size 0.3048 0.381)
			(layers "B.Cu" "B.Mask" "B.Paste")
			(net "GND")
		)
	)
	(footprint ""
		(layer "B.Cu")
		(at 9.181338 -383.051558 -90)
		(property "Reference" "PC6624_1"
			(at 0 0 90)
			(layer "B.SilkS")
			(hide yes)
			(effects
				(font
					(size 1.27 1.27)
				)
				(justify mirror)
			)
		)
		(property "Value" ""
			(at 0 0 90)
			(layer "B.Fab")
			(effects
				(font
					(size 1.27 1.27)
				)
				(justify mirror)
			)
		)
		(duplicate_pad_numbers_are_jumpers no)
		(fp_line
			(start -1.524 0.762)
			(end 1.524 0.762)
			(stroke
				(width 0.1524)
				(type default)
			)
			(layer "B.SilkS")
		)
		(fp_line
			(start 1.524 0.762)
			(end 1.524 -0.762)
			(stroke
				(width 0.1524)
				(type default)
			)
			(layer "B.SilkS")
		)
		(fp_line
			(start -1.524 -0.762)
			(end -1.524 0.762)
			(stroke
				(width 0.1524)
				(type default)
			)
			(layer "B.SilkS")
		)
		(fp_line
			(start 1.524 -0.762)
			(end -1.524 -0.762)
			(stroke
				(width 0.1524)
				(type default)
			)
			(layer "B.SilkS")
		)
		(fp_line
			(start -1.1049 0.724916)
			(end -1.1049 -0.724916)
			(stroke
				(width 0.1)
				(type default)
			)
			(layer "B.Fab")
		)
		(fp_line
			(start 1.1049 0.724916)
			(end -1.1049 0.724916)
			(stroke
				(width 0.1)
				(type default)
			)
			(layer "B.Fab")
		)
		(fp_line
			(start -1.1049 -0.724916)
			(end 1.1049 -0.724916)
			(stroke
				(width 0.1)
				(type default)
			)
			(layer "B.Fab")
		)
		(fp_line
			(start 1.1049 -0.724916)
			(end 1.1049 0.724916)
			(stroke
				(width 0.1)
				(type default)
			)
			(layer "B.Fab")
		)
		(pad "1" smd rect
			(at 0.889 0 270)
			(size 1.016 1.27)
			(layers "B.Cu" "B.Mask" "B.Paste")
			(net "P0V9_CPU1_RT_2D")
		)
		(pad "2" smd rect
			(at -0.889 0 270)
			(size 1.016 1.27)
			(layers "B.Cu" "B.Mask" "B.Paste")
			(net "GND")
		)
	)
	(footprint ""
		(layer "B.Cu")
		(at 161.546286 -388.011162 -90)
		(property "Reference" "C427"
			(at 0 0 90)
			(layer "B.SilkS")
			(hide yes)
			(effects
				(font
					(size 1.27 1.27)
				)
				(justify mirror)
			)
		)
		(property "Value" ""
			(at 0 0 90)
			(layer "B.Fab")
			(effects
				(font
					(size 1.27 1.27)
				)
				(justify mirror)
			)
		)
		(duplicate_pad_numbers_are_jumpers no)
		(fp_line
			(start -0.299974 0.150114)
			(end 0.299974 0.150114)
			(stroke
				(width 0.1)
				(type default)
			)
			(layer "B.Fab")
		)
		(fp_line
			(start 0.299974 0.150114)
			(end 0.299974 -0.150114)
			(stroke
				(width 0.1)
				(type default)
			)
			(layer "B.Fab")
		)
		(fp_line
			(start -0.299974 -0.150114)
			(end -0.299974 0.150114)
			(stroke
				(width 0.1)
				(type default)
			)
			(layer "B.Fab")
		)
		(fp_line
			(start 0.299974 -0.150114)
			(end -0.299974 -0.150114)
			(stroke
				(width 0.1)
				(type default)
			)
			(layer "B.Fab")
		)
		(pad "1" smd rect
			(at 0.2667 0 90)
			(size 0.3048 0.381)
			(layers "B.Cu" "B.Mask" "B.Paste")
			(net "P0V9_CPU1_RT2_2A")
		)
		(pad "2" smd rect
			(at -0.2667 0 90)
			(size 0.3048 0.381)
			(layers "B.Cu" "B.Mask" "B.Paste")
			(net "GND")
		)
	)
	(footprint ""
		(layer "B.Cu")
		(at 103.924354 -186.811412 90)
		(property "Reference" "PC303_4"
			(at 0 0 90)
			(layer "B.SilkS")
			(hide yes)
			(effects
				(font
					(size 1.27 1.27)
				)
				(justify mirror)
			)
		)
		(property "Value" ""
			(at 0 0 90)
			(layer "B.Fab")
			(effects
				(font
					(size 1.27 1.27)
				)
				(justify mirror)
			)
		)
		(duplicate_pad_numbers_are_jumpers no)
		(fp_line
			(start 1.524 -0.762)
			(end -1.524 -0.762)
			(stroke
				(width 0.1524)
				(type default)
			)
			(layer "B.SilkS")
		)
		(fp_line
			(start -1.524 -0.762)
			(end -1.524 0.762)
			(stroke
				(width 0.1524)
				(type default)
			)
			(layer "B.SilkS")
		)
		(fp_line
			(start 1.524 0.762)
			(end 1.524 -0.762)
			(stroke
				(width 0.1524)
				(type default)
			)
			(layer "B.SilkS")
		)
		(fp_line
			(start -1.524 0.762)
			(end 1.524 0.762)
			(stroke
				(width 0.1524)
				(type default)
			)
			(layer "B.SilkS")
		)
		(fp_line
			(start 1.1049 -0.724916)
			(end 1.1049 0.724916)
			(stroke
				(width 0.1)
				(type default)
			)
			(layer "B.Fab")
		)
		(fp_line
			(start -1.1049 -0.724916)
			(end 1.1049 -0.724916)
			(stroke
				(width 0.1)
				(type default)
			)
			(layer "B.Fab")
		)
		(fp_line
			(start 1.1049 0.724916)
			(end -1.1049 0.724916)
			(stroke
				(width 0.1)
				(type default)
			)
			(layer "B.Fab")
		)
		(fp_line
			(start -1.1049 0.724916)
			(end -1.1049 -0.724916)
			(stroke
				(width 0.1)
				(type default)
			)
			(layer "B.Fab")
		)
		(pad "1" smd rect
			(at 0.889 0 90)
			(size 1.016 1.27)
			(layers "B.Cu" "B.Mask" "B.Paste")
			(net "PVDDCR_CPU0_P1")
		)
		(pad "2" smd rect
			(at -0.889 0 90)
			(size 1.016 1.27)
			(layers "B.Cu" "B.Mask" "B.Paste")
			(net "GND")
		)
	)
	(footprint ""
		(layer "B.Cu")
		(at 276.520402 -76.110084 180)
		(property "Reference" ""
			(at 0 0 0)
			(layer "B.SilkS")
			(hide yes)
			(effects
				(font
					(size 1.27 1.27)
				)
				(justify mirror)
			)
		)
		(property "Value" ""
			(at 0 0 0)
			(layer "B.Fab")
			(effects
				(font
					(size 1.27 1.27)
				)
				(justify mirror)
			)
		)
		(duplicate_pad_numbers_are_jumpers no)
		(pad "1" smd circle
			(at 0 0)
			(size 0.9906 0.9906)
			(layers "B.Cu" "B.Mask" "B.Paste")
			(net "Net_2235")
		)
		(zone
			(layer "B.Cu")
			(hatch none 0.5)
			(connect_pads
				(clearance 0)
			)
			(min_thickness 0.25)
			(keepout
				(tracks not_allowed)
				(vias allowed)
				(pads allowed)
				(copperpour not_allowed)
				(footprints allowed)
			)
			(placement
				(enabled no)
				(sheetname "")
			)
			(fill
				(thermal_gap 0.5)
				(thermal_bridge_width 0.5)
				(island_removal_mode 0)
			)
			(polygon
				(pts
					(arc
						(start 278.146002 -76.110084)
						(mid 274.894802 -76.110084)
						(end 278.146002 -76.110084)
					)
				)
			)
		)
	)
)
